(kicad_pcb
	(version 20260206)
	(generator "pcbnew")
	(generator_version "10.0")
	(general
		(thickness 1.6)
		(legacy_teardrops no)
	)
	(paper "A4")
	(title_block
		(title "04192023_DAF0TMB3IC0_F0TG_MB_C_brd_V02_OCP.brd")
		(comment 1 "Grand Teton / footprints 3797-3804 of 8354")
	)
	(layers
		(0 "F.Cu" signal "TOP")
		(4 "In1.Cu" signal "GND")
		(6 "In2.Cu" signal "IN1")
		(8 "In3.Cu" signal "GND1")
		(10 "In4.Cu" signal "IN2")
		(12 "In5.Cu" signal "GND2")
		(14 "In6.Cu" signal "IN3")
		(16 "In7.Cu" signal "GND3")
		(18 "In8.Cu" signal "VCC")
		(20 "In9.Cu" signal "VCC1")
		(22 "In10.Cu" signal "GND4")
		(24 "In11.Cu" signal "IN4")
		(26 "In12.Cu" signal "GND5")
		(28 "In13.Cu" signal "IN5")
		(30 "In14.Cu" signal "GND6")
		(32 "In15.Cu" signal "IN6")
		(34 "In16.Cu" signal "GND7")
		(2 "B.Cu" signal "BOTTOM")
		(9 "F.Adhes" user "F.Adhesive")
		(11 "B.Adhes" user "B.Adhesive")
		(13 "F.Paste" user "Package Geometry/Pastemask Top")
		(15 "B.Paste" user "Package Geometry/Pastemask Bottom")
		(5 "F.SilkS" user "Ref Des/Silkscreen Top")
		(7 "B.SilkS" user "Ref Des/Silkscreen Bottom")
		(1 "F.Mask" user "Board Geometry/Soldermask Top")
		(3 "B.Mask" user "Board Geometry/Soldermask Bottom")
		(17 "Dwgs.User" user "User.Drawings")
		(19 "Cmts.User" user "User.Comments")
		(21 "Eco1.User" user "User.Eco1")
		(23 "Eco2.User" user "User.Eco2")
		(25 "Edge.Cuts" user "Board Geometry/Outline")
		(27 "Margin" user)
		(31 "F.CrtYd" user "Package Geometry/Place Bound Top")
		(29 "B.CrtYd" user "Package Geometry/Place Bound Bottom")
		(35 "F.Fab" user "Ref Des/Assembly Top")
		(33 "B.Fab" user "Ref Des/Assembly Bottom")
	)
	(footprint ""
		(layer "F.Cu")
		(at 363.008926 -28.273502 90)
		(property "Reference" "R1419"
			(at 0 0 90)
			(layer "F.SilkS")
			(hide yes)
			(effects
				(font
					(size 1.27 1.27)
				)
			)
		)
		(property "Value" ""
			(at 0 0 90)
			(layer "F.Fab")
			(effects
				(font
					(size 1.27 1.27)
				)
			)
		)
		(duplicate_pad_numbers_are_jumpers no)
		(fp_line
			(start 0.7874 -0.4064)
			(end 0.7874 0.4064)
			(stroke
				(width 0.1524)
				(type default)
			)
			(layer "F.SilkS")
		)
		(fp_line
			(start -0.7874 -0.4064)
			(end 0.7874 -0.4064)
			(stroke
				(width 0.1524)
				(type default)
			)
			(layer "F.SilkS")
		)
		(fp_line
			(start 0.7874 0.4064)
			(end -0.7874 0.4064)
			(stroke
				(width 0.1524)
				(type default)
			)
			(layer "F.SilkS")
		)
		(fp_line
			(start -0.7874 0.4064)
			(end -0.7874 -0.4064)
			(stroke
				(width 0.1524)
				(type default)
			)
			(layer "F.SilkS")
		)
		(fp_line
			(start -0.12065 -0.305054)
			(end -0.12065 -0.2794)
			(stroke
				(width 0.1)
				(type default)
			)
			(layer "F.Fab")
		)
		(fp_line
			(start -0.67945 -0.305054)
			(end -0.12065 -0.305054)
			(stroke
				(width 0.1)
				(type default)
			)
			(layer "F.Fab")
		)
		(fp_line
			(start 0.67945 -0.3048)
			(end 0.67945 0.3048)
			(stroke
				(width 0.1)
				(type default)
			)
			(layer "F.Fab")
		)
		(fp_line
			(start 0.12065 -0.3048)
			(end 0.67945 -0.3048)
			(stroke
				(width 0.1)
				(type default)
			)
			(layer "F.Fab")
		)
		(fp_line
			(start 0.12065 -0.2794)
			(end 0.12065 -0.3048)
			(stroke
				(width 0.1)
				(type default)
			)
			(layer "F.Fab")
		)
		(fp_line
			(start -0.12065 -0.2794)
			(end 0.12065 -0.2794)
			(stroke
				(width 0.1)
				(type default)
			)
			(layer "F.Fab")
		)
		(fp_line
			(start 0.120396 0.2794)
			(end -0.12065 0.2794)
			(stroke
				(width 0.1)
				(type default)
			)
			(layer "F.Fab")
		)
		(fp_line
			(start -0.12065 0.2794)
			(end -0.12065 0.3048)
			(stroke
				(width 0.1)
				(type default)
			)
			(layer "F.Fab")
		)
		(fp_line
			(start 0.67945 0.3048)
			(end 0.120396 0.3048)
			(stroke
				(width 0.1)
				(type default)
			)
			(layer "F.Fab")
		)
		(fp_line
			(start 0.120396 0.3048)
			(end 0.120396 0.2794)
			(stroke
				(width 0.1)
				(type default)
			)
			(layer "F.Fab")
		)
		(fp_line
			(start -0.12065 0.3048)
			(end -0.67945 0.3048)
			(stroke
				(width 0.1)
				(type default)
			)
			(layer "F.Fab")
		)
		(fp_line
			(start -0.67945 0.3048)
			(end -0.67945 -0.305054)
			(stroke
				(width 0.1)
				(type default)
			)
			(layer "F.Fab")
		)
		(pad "1" smd circle
			(at -0.40005 0 90)
			(size 0 0)
			(layers "F.Cu" "F.Mask" "F.Paste")
			(net "PVDD18_S5_P0")
		)
		(pad "2" smd circle
			(at 0.40005 0 90)
			(size 0 0)
			(layers "F.Cu" "F.Mask" "F.Paste")
			(net "UART_LS_EN_R_N")
		)
	)
	(footprint ""
		(layer "F.Cu")
		(at 177.81016 -391.6172)
		(property "Reference" "R1490"
			(at 0 0 0)
			(layer "F.SilkS")
			(hide yes)
			(effects
				(font
					(size 1.27 1.27)
				)
			)
		)
		(property "Value" ""
			(at 0 0 0)
			(layer "F.Fab")
			(effects
				(font
					(size 1.27 1.27)
				)
			)
		)
		(duplicate_pad_numbers_are_jumpers no)
		(fp_line
			(start -0.32512 -0.175006)
			(end 0.32512 -0.175006)
			(stroke
				(width 0.1)
				(type default)
			)
			(layer "F.Fab")
		)
		(fp_line
			(start -0.32512 0.175006)
			(end -0.32512 -0.175006)
			(stroke
				(width 0.1)
				(type default)
			)
			(layer "F.Fab")
		)
		(fp_line
			(start 0.32512 -0.175006)
			(end 0.32512 0.175006)
			(stroke
				(width 0.1)
				(type default)
			)
			(layer "F.Fab")
		)
		(fp_line
			(start 0.32512 0.175006)
			(end -0.32512 0.175006)
			(stroke
				(width 0.1)
				(type default)
			)
			(layer "F.Fab")
		)
		(pad "1" smd rect
			(at -0.2667 0)
			(size 0.3048 0.381)
			(layers "F.Cu" "F.Mask" "F.Paste")
			(net "P1V8_CPU1_RT_1D")
		)
		(pad "2" smd rect
			(at 0.2667 0 180)
			(size 0.3048 0.381)
			(layers "F.Cu" "F.Mask" "F.Paste")
			(net "JTAG_TDO_RT_CPU1_P2")
		)
	)
	(footprint ""
		(layer "F.Cu")
		(at 28.967684 -52.004214)
		(property "Reference" "J49"
			(at -1.016 -3.495548 0)
			(unlocked yes)
			(layer "F.SilkS")
			(effects
				(font
					(size 0.7874 0.5842)
					(thickness 0.1524)
				)
			)
		)
		(property "Value" ""
			(at 0 0 0)
			(layer "F.Fab")
			(effects
				(font
					(size 1.27 1.27)
				)
			)
		)
		(duplicate_pad_numbers_are_jumpers no)
		(fp_line
			(start -1.700022 -2.739898)
			(end 1.700022 -2.739898)
			(stroke
				(width 0.1524)
				(type default)
			)
			(layer "F.SilkS")
		)
		(fp_line
			(start -1.700022 -2.4257)
			(end -1.700022 -2.739898)
			(stroke
				(width 0.1524)
				(type default)
			)
			(layer "F.SilkS")
		)
		(fp_line
			(start -1.700022 -1.1557)
			(end -1.700022 -1.3843)
			(stroke
				(width 0.1524)
				(type default)
			)
			(layer "F.SilkS")
		)
		(fp_line
			(start -1.700022 0.1143)
			(end -1.700022 -0.1143)
			(stroke
				(width 0.1524)
				(type default)
			)
			(layer "F.SilkS")
		)
		(fp_line
			(start -1.700022 1.3843)
			(end -1.700022 1.1557)
			(stroke
				(width 0.1524)
				(type default)
			)
			(layer "F.SilkS")
		)
		(fp_line
			(start -1.700022 2.739898)
			(end -1.700022 2.4257)
			(stroke
				(width 0.1524)
				(type default)
			)
			(layer "F.SilkS")
		)
		(fp_line
			(start 1.700022 -2.739898)
			(end 1.700022 -2.4257)
			(stroke
				(width 0.1524)
				(type default)
			)
			(layer "F.SilkS")
		)
		(fp_line
			(start 1.700022 -1.3843)
			(end 1.700022 -1.1557)
			(stroke
				(width 0.1524)
				(type default)
			)
			(layer "F.SilkS")
		)
		(fp_line
			(start 1.700022 -0.1143)
			(end 1.700022 0.1143)
			(stroke
				(width 0.1524)
				(type default)
			)
			(layer "F.SilkS")
		)
		(fp_line
			(start 1.700022 1.1557)
			(end 1.700022 1.3843)
			(stroke
				(width 0.1524)
				(type default)
			)
			(layer "F.SilkS")
		)
		(fp_line
			(start 1.700022 2.4257)
			(end 1.700022 2.739898)
			(stroke
				(width 0.1524)
				(type default)
			)
			(layer "F.SilkS")
		)
		(fp_line
			(start 1.700022 2.739898)
			(end -1.700022 2.739898)
			(stroke
				(width 0.1524)
				(type default)
			)
			(layer "F.SilkS")
		)
		(fp_poly
			(pts
				(xy -3.383534 -1.905) (xy -4.399534 -1.397) (xy -4.399534 -2.413)
			)
			(stroke
				(width 0)
				(type default)
			)
			(fill yes)
			(layer "F.SilkS")
		)
		(fp_line
			(start -1.700022 -2.739898)
			(end 1.700022 -2.739898)
			(stroke
				(width 0.1)
				(type default)
			)
			(layer "F.Fab")
		)
		(fp_line
			(start -1.700022 2.739898)
			(end -1.700022 -2.739898)
			(stroke
				(width 0.1)
				(type default)
			)
			(layer "F.Fab")
		)
		(fp_line
			(start 1.700022 -2.739898)
			(end 1.700022 2.739898)
			(stroke
				(width 0.1)
				(type default)
			)
			(layer "F.Fab")
		)
		(fp_line
			(start 1.700022 2.739898)
			(end -1.700022 2.739898)
			(stroke
				(width 0.1)
				(type default)
			)
			(layer "F.Fab")
		)
		(fp_poly
			(pts
				(xy -4.399534 -2.413) (xy -4.399534 -1.397) (xy -3.383534 -1.905)
			)
			(stroke
				(width 0)
				(type default)
			)
			(fill yes)
			(layer "F.Fab")
		)
		(pad "1" smd rect
			(at -2.050034 -1.905 270)
			(size 0.762 2.413)
			(layers "F.Cu" "F.Mask" "F.Paste")
			(net "CPU1_BP0")
		)
		(pad "2" smd rect
			(at 2.050034 -1.905 270)
			(size 0.762 2.413)
			(layers "F.Cu" "F.Mask" "F.Paste")
			(net "GND")
		)
		(pad "3" smd rect
			(at -2.050034 -0.635 270)
			(size 0.762 2.413)
			(layers "F.Cu" "F.Mask" "F.Paste")
			(net "CPU1_BP1")
		)
		(pad "4" smd rect
			(at 2.050034 -0.635 270)
			(size 0.762 2.413)
			(layers "F.Cu" "F.Mask" "F.Paste")
			(net "GND")
		)
		(pad "5" smd rect
			(at -2.050034 0.635 270)
			(size 0.762 2.413)
			(layers "F.Cu" "F.Mask" "F.Paste")
			(net "CPU1_BP2")
		)
		(pad "6" smd rect
			(at 2.050034 0.635 270)
			(size 0.762 2.413)
			(layers "F.Cu" "F.Mask" "F.Paste")
			(net "GND")
		)
		(pad "7" smd rect
			(at -2.050034 1.905 270)
			(size 0.762 2.413)
			(layers "F.Cu" "F.Mask" "F.Paste")
			(net "CPU1_BP3")
		)
		(pad "8" smd rect
			(at 2.050034 1.905 270)
			(size 0.762 2.413)
			(layers "F.Cu" "F.Mask" "F.Paste")
			(net "GND")
		)
	)
	(footprint ""
		(layer "F.Cu")
		(at 334.028288 -402.548852 -90)
		(property "Reference" "R1006"
			(at 0 0 270)
			(layer "F.SilkS")
			(hide yes)
			(effects
				(font
					(size 1.27 1.27)
				)
			)
		)
		(property "Value" ""
			(at 0 0 270)
			(layer "F.Fab")
			(effects
				(font
					(size 1.27 1.27)
				)
			)
		)
		(duplicate_pad_numbers_are_jumpers no)
		(fp_line
			(start -0.32512 0.175006)
			(end -0.32512 -0.175006)
			(stroke
				(width 0.1)
				(type default)
			)
			(layer "F.Fab")
		)
		(fp_line
			(start 0.32512 0.175006)
			(end -0.32512 0.175006)
			(stroke
				(width 0.1)
				(type default)
			)
			(layer "F.Fab")
		)
		(fp_line
			(start -0.32512 -0.175006)
			(end 0.32512 -0.175006)
			(stroke
				(width 0.1)
				(type default)
			)
			(layer "F.Fab")
		)
		(fp_line
			(start 0.32512 -0.175006)
			(end 0.32512 0.175006)
			(stroke
				(width 0.1)
				(type default)
			)
			(layer "F.Fab")
		)
		(pad "1" smd rect
			(at -0.2667 0 270)
			(size 0.3048 0.381)
			(layers "F.Cu" "F.Mask" "F.Paste")
			(net "MODE_RT_CPU0_P1")
		)
		(pad "2" smd rect
			(at 0.2667 0 90)
			(size 0.3048 0.381)
			(layers "F.Cu" "F.Mask" "F.Paste")
			(net "GND")
		)
	)
	(footprint ""
		(layer "F.Cu")
		(at 336.172556 -133.75005)
		(property "Reference" "PC81"
			(at 0 0 0)
			(layer "F.SilkS")
			(hide yes)
			(effects
				(font
					(size 1.27 1.27)
				)
			)
		)
		(property "Value" ""
			(at 0 0 0)
			(layer "F.Fab")
			(effects
				(font
					(size 1.27 1.27)
				)
			)
		)
		(duplicate_pad_numbers_are_jumpers no)
		(fp_line
			(start -1.524 -0.762)
			(end 1.524 -0.762)
			(stroke
				(width 0.1524)
				(type default)
			)
			(layer "F.SilkS")
		)
		(fp_line
			(start -1.524 0.762)
			(end -1.524 -0.762)
			(stroke
				(width 0.1524)
				(type default)
			)
			(layer "F.SilkS")
		)
		(fp_line
			(start 1.524 -0.762)
			(end 1.524 0.762)
			(stroke
				(width 0.1524)
				(type default)
			)
			(layer "F.SilkS")
		)
		(fp_line
			(start 1.524 0.762)
			(end -1.524 0.762)
			(stroke
				(width 0.1524)
				(type default)
			)
			(layer "F.SilkS")
		)
		(fp_line
			(start -1.1049 -0.724916)
			(end -1.1049 0.724916)
			(stroke
				(width 0.1)
				(type default)
			)
			(layer "F.Fab")
		)
		(fp_line
			(start -1.1049 0.724916)
			(end 1.1049 0.724916)
			(stroke
				(width 0.1)
				(type default)
			)
			(layer "F.Fab")
		)
		(fp_line
			(start 1.1049 -0.724916)
			(end -1.1049 -0.724916)
			(stroke
				(width 0.1)
				(type default)
			)
			(layer "F.Fab")
		)
		(fp_line
			(start 1.1049 0.724916)
			(end 1.1049 -0.724916)
			(stroke
				(width 0.1)
				(type default)
			)
			(layer "F.Fab")
		)
		(pad "1" smd rect
			(at -0.889 0 180)
			(size 1.016 1.27)
			(layers "F.Cu" "F.Mask" "F.Paste")
			(net "SW_P12V_AUX_PVDD18_S5_P0_FLT")
		)
		(pad "2" smd rect
			(at 0.889 0 180)
			(size 1.016 1.27)
			(layers "F.Cu" "F.Mask" "F.Paste")
			(net "GND")
		)
	)
	(footprint ""
		(layer "F.Cu")
		(at 426.230796 -394.7668)
		(property "Reference" "C666"
			(at 0 0 0)
			(layer "F.SilkS")
			(hide yes)
			(effects
				(font
					(size 1.27 1.27)
				)
			)
		)
		(property "Value" ""
			(at 0 0 0)
			(layer "F.Fab")
			(effects
				(font
					(size 1.27 1.27)
				)
			)
		)
		(duplicate_pad_numbers_are_jumpers no)
		(fp_line
			(start -1.524 -0.762)
			(end 1.524 -0.762)
			(stroke
				(width 0.1524)
				(type default)
			)
			(layer "F.SilkS")
		)
		(fp_line
			(start -1.524 0.762)
			(end -1.524 -0.762)
			(stroke
				(width 0.1524)
				(type default)
			)
			(layer "F.SilkS")
		)
		(fp_line
			(start 1.524 -0.762)
			(end 1.524 0.762)
			(stroke
				(width 0.1524)
				(type default)
			)
			(layer "F.SilkS")
		)
		(fp_line
			(start 1.524 0.762)
			(end -1.524 0.762)
			(stroke
				(width 0.1524)
				(type default)
			)
			(layer "F.SilkS")
		)
		(fp_line
			(start -1.1049 -0.724916)
			(end -1.1049 0.724916)
			(stroke
				(width 0.1)
				(type default)
			)
			(layer "F.Fab")
		)
		(fp_line
			(start -1.1049 0.724916)
			(end 1.1049 0.724916)
			(stroke
				(width 0.1)
				(type default)
			)
			(layer "F.Fab")
		)
		(fp_line
			(start 1.1049 -0.724916)
			(end -1.1049 -0.724916)
			(stroke
				(width 0.1)
				(type default)
			)
			(layer "F.Fab")
		)
		(fp_line
			(start 1.1049 0.724916)
			(end 1.1049 -0.724916)
			(stroke
				(width 0.1)
				(type default)
			)
			(layer "F.Fab")
		)
		(pad "1" smd rect
			(at -0.889 0 180)
			(size 1.016 1.27)
			(layers "F.Cu" "F.Mask" "F.Paste")
			(net "P1V8_CPU0_RT2_1A")
		)
		(pad "2" smd rect
			(at 0.889 0 180)
			(size 1.016 1.27)
			(layers "F.Cu" "F.Mask" "F.Paste")
			(net "GND")
		)
	)
	(footprint ""
		(layer "F.Cu")
		(at 198.247 -92.456)
		(property "Reference" "R8089"
			(at 0 0 0)
			(layer "F.SilkS")
			(hide yes)
			(effects
				(font
					(size 1.27 1.27)
				)
			)
		)
		(property "Value" ""
			(at 0 0 0)
			(layer "F.Fab")
			(effects
				(font
					(size 1.27 1.27)
				)
			)
		)
		(duplicate_pad_numbers_are_jumpers no)
		(fp_line
			(start -0.7874 -0.4064)
			(end 0.7874 -0.4064)
			(stroke
				(width 0.1524)
				(type default)
			)
			(layer "F.SilkS")
		)
		(fp_line
			(start -0.7874 0.4064)
			(end -0.7874 -0.4064)
			(stroke
				(width 0.1524)
				(type default)
			)
			(layer "F.SilkS")
		)
		(fp_line
			(start 0.7874 -0.4064)
			(end 0.7874 0.4064)
			(stroke
				(width 0.1524)
				(type default)
			)
			(layer "F.SilkS")
		)
		(fp_line
			(start 0.7874 0.4064)
			(end -0.7874 0.4064)
			(stroke
				(width 0.1524)
				(type default)
			)
			(layer "F.SilkS")
		)
		(fp_line
			(start -0.67945 -0.305054)
			(end -0.12065 -0.305054)
			(stroke
				(width 0.1)
				(type default)
			)
			(layer "F.Fab")
		)
		(fp_line
			(start -0.67945 0.3048)
			(end -0.67945 -0.305054)
			(stroke
				(width 0.1)
				(type default)
			)
			(layer "F.Fab")
		)
		(fp_line
			(start -0.12065 -0.305054)
			(end -0.12065 -0.2794)
			(stroke
				(width 0.1)
				(type default)
			)
			(layer "F.Fab")
		)
		(fp_line
			(start -0.12065 -0.2794)
			(end 0.12065 -0.2794)
			(stroke
				(width 0.1)
				(type default)
			)
			(layer "F.Fab")
		)
		(fp_line
			(start -0.12065 0.2794)
			(end -0.12065 0.3048)
			(stroke
				(width 0.1)
				(type default)
			)
			(layer "F.Fab")
		)
		(fp_line
			(start -0.12065 0.3048)
			(end -0.67945 0.3048)
			(stroke
				(width 0.1)
				(type default)
			)
			(layer "F.Fab")
		)
		(fp_line
			(start 0.120396 0.2794)
			(end -0.12065 0.2794)
			(stroke
				(width 0.1)
				(type default)
			)
			(layer "F.Fab")
		)
		(fp_line
			(start 0.120396 0.3048)
			(end 0.120396 0.2794)
			(stroke
				(width 0.1)
				(type default)
			)
			(layer "F.Fab")
		)
		(fp_line
			(start 0.12065 -0.3048)
			(end 0.67945 -0.3048)
			(stroke
				(width 0.1)
				(type default)
			)
			(layer "F.Fab")
		)
		(fp_line
			(start 0.12065 -0.2794)
			(end 0.12065 -0.3048)
			(stroke
				(width 0.1)
				(type default)
			)
			(layer "F.Fab")
		)
		(fp_line
			(start 0.67945 -0.3048)
			(end 0.67945 0.3048)
			(stroke
				(width 0.1)
				(type default)
			)
			(layer "F.Fab")
		)
		(fp_line
			(start 0.67945 0.3048)
			(end 0.120396 0.3048)
			(stroke
				(width 0.1)
				(type default)
			)
			(layer "F.Fab")
		)
		(pad "1" smd circle
			(at -0.40005 0)
			(size 0 0)
			(layers "F.Cu" "F.Mask" "F.Paste")
			(net "PWRGD_CHGL_CPU1")
		)
		(pad "2" smd circle
			(at 0.40005 0)
			(size 0 0)
			(layers "F.Cu" "F.Mask" "F.Paste")
			(net "PWRGD_CHGL_CPU1_R1")
		)
	)
	(footprint ""
		(layer "F.Cu")
		(at 196.729858 -77.06614 180)
		(property "Reference" "R79"
			(at 0 0 180)
			(layer "F.SilkS")
			(hide yes)
			(effects
				(font
					(size 1.27 1.27)
				)
			)
		)
		(property "Value" ""
			(at 0 0 180)
			(layer "F.Fab")
			(effects
				(font
					(size 1.27 1.27)
				)
			)
		)
		(duplicate_pad_numbers_are_jumpers no)
		(fp_line
			(start 0.7874 0.4064)
			(end -0.7874 0.4064)
			(stroke
				(width 0.1524)
				(type default)
			)
			(layer "F.SilkS")
		)
		(fp_line
			(start 0.7874 -0.4064)
			(end 0.7874 0.4064)
			(stroke
				(width 0.1524)
				(type default)
			)
			(layer "F.SilkS")
		)
		(fp_line
			(start -0.7874 0.4064)
			(end -0.7874 -0.4064)
			(stroke
				(width 0.1524)
				(type default)
			)
			(layer "F.SilkS")
		)
		(fp_line
			(start -0.7874 -0.4064)
			(end 0.7874 -0.4064)
			(stroke
				(width 0.1524)
				(type default)
			)
			(layer "F.SilkS")
		)
		(fp_line
			(start 0.67945 0.3048)
			(end 0.120396 0.3048)
			(stroke
				(width 0.1)
				(type default)
			)
			(layer "F.Fab")
		)
		(fp_line
			(start 0.67945 -0.3048)
			(end 0.67945 0.3048)
			(stroke
				(width 0.1)
				(type default)
			)
			(layer "F.Fab")
		)
		(fp_line
			(start 0.12065 -0.2794)
			(end 0.12065 -0.3048)
			(stroke
				(width 0.1)
				(type default)
			)
			(layer "F.Fab")
		)
		(fp_line
			(start 0.12065 -0.3048)
			(end 0.67945 -0.3048)
			(stroke
				(width 0.1)
				(type default)
			)
			(layer "F.Fab")
		)
		(fp_line
			(start 0.120396 0.3048)
			(end 0.120396 0.2794)
			(stroke
				(width 0.1)
				(type default)
			)
			(layer "F.Fab")
		)
		(fp_line
			(start 0.120396 0.2794)
			(end -0.12065 0.2794)
			(stroke
				(width 0.1)
				(type default)
			)
			(layer "F.Fab")
		)
		(fp_line
			(start -0.12065 0.3048)
			(end -0.67945 0.3048)
			(stroke
				(width 0.1)
				(type default)
			)
			(layer "F.Fab")
		)
		(fp_line
			(start -0.12065 0.2794)
			(end -0.12065 0.3048)
			(stroke
				(width 0.1)
				(type default)
			)
			(layer "F.Fab")
		)
		(fp_line
			(start -0.12065 -0.2794)
			(end 0.12065 -0.2794)
			(stroke
				(width 0.1)
				(type default)
			)
			(layer "F.Fab")
		)
		(fp_line
			(start -0.12065 -0.305054)
			(end -0.12065 -0.2794)
			(stroke
				(width 0.1)
				(type default)
			)
			(layer "F.Fab")
		)
		(fp_line
			(start -0.67945 0.3048)
			(end -0.67945 -0.305054)
			(stroke
				(width 0.1)
				(type default)
			)
			(layer "F.Fab")
		)
		(fp_line
			(start -0.67945 -0.305054)
			(end -0.12065 -0.305054)
			(stroke
				(width 0.1)
				(type default)
			)
			(layer "F.Fab")
		)
		(pad "1" smd circle
			(at -0.40005 0 180)
			(size 0 0)
			(layers "F.Cu" "F.Mask" "F.Paste")
			(net "RMII_OCP_BMC_RXD_0")
		)
		(pad "2" smd circle
			(at 0.40005 0 180)
			(size 0 0)
			(layers "F.Cu" "F.Mask" "F.Paste")
			(net "GND")
		)
	)
)
